(kicad_pcb
	(version 20260206)
	(generator "pcbnew")
	(generator_version "10.0")
	(general
		(thickness 1.6)
		(legacy_teardrops no)
	)
	(paper "A4")
	(title_block
		(title "Wiwynn_Tioga_Pass_MB.brd")
		(comment 1 "Tioga Pass / footprints 753-759 of 4770")
	)
	(layers
		(0 "F.Cu" signal "TOP")
		(4 "In1.Cu" signal "L2GND")
		(6 "In2.Cu" signal "L3")
		(8 "In3.Cu" signal "L4GND")
		(10 "In4.Cu" signal "L5")
		(12 "In5.Cu" signal "L6GND")
		(14 "In6.Cu" signal "L7VCC")
		(16 "In7.Cu" signal "L8VCC")
		(18 "In8.Cu" signal "L9GND")
		(20 "In9.Cu" signal "L10")
		(22 "In10.Cu" signal "L11GND")
		(24 "In11.Cu" signal "L12")
		(26 "In12.Cu" signal "L13GND")
		(2 "B.Cu" signal "BOTTOM")
		(9 "F.Adhes" user "F.Adhesive")
		(11 "B.Adhes" user "B.Adhesive")
		(13 "F.Paste" user "Package Geometry/Pastemask Top")
		(15 "B.Paste" user "Package Geometry/Pastemask Bottom")
		(5 "F.SilkS" user "Ref Des/Silkscreen Top")
		(7 "B.SilkS" user "Ref Des/Silkscreen Bottom")
		(1 "F.Mask" user "Board Geometry/Soldermask Top")
		(3 "B.Mask" user "Board Geometry/Soldermask Bottom")
		(17 "Dwgs.User" user "User.Drawings")
		(19 "Cmts.User" user "User.Comments")
		(21 "Eco1.User" user "User.Eco1")
		(23 "Eco2.User" user "User.Eco2")
		(25 "Edge.Cuts" user "Board Geometry/Outline")
		(27 "Margin" user)
		(31 "F.CrtYd" user "Package Geometry/Place Bound Top")
		(29 "B.CrtYd" user "Package Geometry/Place Bound Bottom")
		(35 "F.Fab" user "Ref Des/Assembly Top")
		(33 "B.Fab" user "Ref Des/Assembly Bottom")
	)
	(footprint ""
		(layer "F.Cu")
		(at 320.6115 -123.317 -90)
		(property "Reference" "C831"
			(at -0.8382 -0.67818 270)
			(unlocked yes)
			(layer "F.SilkS")
			(effects
				(font
					(size 0.4064 0.254)
					(thickness 0.1524)
				)
				(justify left)
			)
		)
		(property "Value" ""
			(at 0 0 270)
			(layer "F.Fab")
			(effects
				(font
					(size 1.27 1.27)
				)
			)
		)
		(duplicate_pad_numbers_are_jumpers no)
		(fp_poly
			(pts
				(xy 0.3048 -0.1016) (xy 0.3048 0.9906) (xy -0.3048 0.9906) (xy -0.3048 -0.1016)
			)
			(stroke
				(width 0)
				(type default)
			)
			(fill no)
			(layer "F.CrtYd")
		)
		(fp_line
			(start -0.3048 0.9906)
			(end 0.3048 0.9906)
			(stroke
				(width 0.1)
				(type default)
			)
			(layer "F.Fab")
		)
		(fp_line
			(start 0.3048 0.9906)
			(end 0.3048 -0.1016)
			(stroke
				(width 0.1)
				(type default)
			)
			(layer "F.Fab")
		)
		(fp_line
			(start -0.3048 -0.1016)
			(end -0.3048 0.9906)
			(stroke
				(width 0.1)
				(type default)
			)
			(layer "F.Fab")
		)
		(fp_line
			(start 0.3048 -0.1016)
			(end -0.3048 -0.1016)
			(stroke
				(width 0.1)
				(type default)
			)
			(layer "F.Fab")
		)
		(pad "1" smd rect
			(at 0 0 270)
			(size 0.508 0.508)
			(layers "F.Cu" "F.Mask" "F.Paste")
			(net "P3E_CPU0_PE1_PCH_TXP<15>")
		)
		(pad "2" smd rect
			(at 0 0.889 270)
			(size 0.508 0.508)
			(layers "F.Cu" "F.Mask" "F.Paste")
			(net "P3E_CPU0_PE1_PCH_CON_TXP<15>")
		)
		(zone
			(layer "F.Cu")
			(hatch none 0.5)
			(connect_pads
				(clearance 0)
			)
			(min_thickness 0.25)
			(keepout
				(tracks not_allowed)
				(vias allowed)
				(pads allowed)
				(copperpour not_allowed)
				(footprints allowed)
			)
			(placement
				(enabled no)
				(sheetname "")
			)
			(fill
				(thermal_gap 0.5)
				(thermal_bridge_width 0.5)
				(island_removal_mode 0)
			)
			(polygon
				(pts
					(xy 319.9765 -123.571) (xy 319.9765 -123.063) (xy 320.3575 -123.063) (xy 320.3575 -123.571)
				)
			)
		)
		(zone
			(layer "F.Cu")
			(hatch none 0.5)
			(connect_pads
				(clearance 0)
			)
			(min_thickness 0.25)
			(keepout
				(tracks allowed)
				(vias not_allowed)
				(pads allowed)
				(copperpour not_allowed)
				(footprints allowed)
			)
			(placement
				(enabled no)
				(sheetname "")
			)
			(fill
				(thermal_gap 0.5)
				(thermal_bridge_width 0.5)
				(island_removal_mode 0)
			)
			(polygon
				(pts
					(xy 320.3575 -123.571) (xy 320.3575 -123.063) (xy 319.9765 -123.063) (xy 319.9765 -123.571)
				)
			)
		)
	)
	(footprint ""
		(layer "F.Cu")
		(at 394.457682 -144.255998 90)
		(property "Reference" "C8A13"
			(at 0 0 90)
			(layer "F.SilkS")
			(hide yes)
			(effects
				(font
					(size 1.27 1.27)
				)
			)
		)
		(property "Value" ""
			(at 0 0 90)
			(layer "F.Fab")
			(effects
				(font
					(size 1.27 1.27)
				)
			)
		)
		(duplicate_pad_numbers_are_jumpers no)
		(fp_poly
			(pts
				(xy -0.7239 -0.2159) (xy 0.7239 -0.2159) (xy 0.7239 1.9939) (xy -0.7239 1.9939)
			)
			(stroke
				(width 0)
				(type default)
			)
			(fill no)
			(layer "F.CrtYd")
		)
		(fp_line
			(start 0.7239 -0.2159)
			(end -0.7239 -0.2159)
			(stroke
				(width 0.1)
				(type default)
			)
			(layer "F.Fab")
		)
		(fp_line
			(start -0.7239 -0.2159)
			(end -0.7239 1.9939)
			(stroke
				(width 0.1)
				(type default)
			)
			(layer "F.Fab")
		)
		(fp_line
			(start 0.7239 1.9939)
			(end 0.7239 -0.2159)
			(stroke
				(width 0.1)
				(type default)
			)
			(layer "F.Fab")
		)
		(fp_line
			(start -0.7239 1.9939)
			(end 0.7239 1.9939)
			(stroke
				(width 0.1)
				(type default)
			)
			(layer "F.Fab")
		)
		(pad "1" smd rect
			(at 0 0 90)
			(size 1.27 1.016)
			(layers "F.Cu" "F.Mask" "F.Paste")
			(net "P1V05_PCH_STBY")
		)
		(pad "2" smd rect
			(at 0 1.778 90)
			(size 1.27 1.016)
			(layers "F.Cu" "F.Mask" "F.Paste")
			(net "GND")
		)
		(zone
			(layer "F.Cu")
			(hatch none 0.5)
			(connect_pads
				(clearance 0)
			)
			(min_thickness 0.25)
			(keepout
				(tracks not_allowed)
				(vias allowed)
				(pads allowed)
				(copperpour not_allowed)
				(footprints allowed)
			)
			(placement
				(enabled no)
				(sheetname "")
			)
			(fill
				(thermal_gap 0.5)
				(thermal_bridge_width 0.5)
				(island_removal_mode 0)
			)
			(polygon
				(pts
					(xy 394.965682 -143.620998) (xy 394.965682 -144.890998) (xy 395.727682 -144.890998) (xy 395.727682 -143.620998)
				)
			)
		)
	)
	(footprint ""
		(layer "F.Cu")
		(at 15.875 -71.247 -90)
		(property "Reference" "C1D22"
			(at 0 0 270)
			(layer "F.SilkS")
			(hide yes)
			(effects
				(font
					(size 1.27 1.27)
				)
			)
		)
		(property "Value" ""
			(at 0 0 270)
			(layer "F.Fab")
			(effects
				(font
					(size 1.27 1.27)
				)
			)
		)
		(duplicate_pad_numbers_are_jumpers no)
		(fp_rect
			(start 0.3048 0.9906)
			(end -0.3048 -0.1016)
			(stroke
				(width 0)
				(type default)
			)
			(fill no)
			(layer "F.CrtYd")
		)
		(fp_line
			(start -0.3048 0.9906)
			(end 0.3048 0.9906)
			(stroke
				(width 0.1)
				(type default)
			)
			(layer "F.Fab")
		)
		(fp_line
			(start 0.3048 0.9906)
			(end 0.3048 -0.1016)
			(stroke
				(width 0.1)
				(type default)
			)
			(layer "F.Fab")
		)
		(fp_line
			(start -0.3048 -0.1016)
			(end -0.3048 0.9906)
			(stroke
				(width 0.1)
				(type default)
			)
			(layer "F.Fab")
		)
		(fp_line
			(start 0.3048 -0.1016)
			(end -0.3048 -0.1016)
			(stroke
				(width 0.1)
				(type default)
			)
			(layer "F.Fab")
		)
		(pad "1" smd rect
			(at 0 0 270)
			(size 0.508 0.508)
			(layers "F.Cu" "F.Mask" "F.Paste")
			(net "A_HSC_MON")
		)
		(pad "2" smd rect
			(at 0 0.889 270)
			(size 0.508 0.508)
			(layers "F.Cu" "F.Mask" "F.Paste")
			(net "A_HSC_MOP")
		)
		(zone
			(layer "F.Cu")
			(hatch none 0.5)
			(connect_pads
				(clearance 0)
			)
			(min_thickness 0.25)
			(keepout
				(tracks allowed)
				(vias not_allowed)
				(pads allowed)
				(copperpour not_allowed)
				(footprints allowed)
			)
			(placement
				(enabled no)
				(sheetname "")
			)
			(fill
				(thermal_gap 0.5)
				(thermal_bridge_width 0.5)
				(island_removal_mode 0)
			)
			(polygon
				(pts
					(xy 15.24 -70.993) (xy 15.621 -70.993) (xy 15.621 -71.501) (xy 15.24 -71.501)
				)
			)
		)
		(zone
			(layer "F.Cu")
			(hatch none 0.5)
			(connect_pads
				(clearance 0)
			)
			(min_thickness 0.25)
			(keepout
				(tracks not_allowed)
				(vias allowed)
				(pads allowed)
				(copperpour not_allowed)
				(footprints allowed)
			)
			(placement
				(enabled no)
				(sheetname "")
			)
			(fill
				(thermal_gap 0.5)
				(thermal_bridge_width 0.5)
				(island_removal_mode 0)
			)
			(polygon
				(pts
					(xy 15.24 -70.993) (xy 15.621 -70.993) (xy 15.621 -71.501) (xy 15.24 -71.501)
				)
			)
		)
	)
	(footprint ""
		(layer "F.Cu")
		(at 194.457828 -78.000352)
		(property "Reference" "CT40"
			(at -0.56007 -5.2324 270)
			(unlocked yes)
			(layer "F.SilkS")
			(effects
				(font
					(size 0.7874 0.5842)
					(thickness 0.1524)
				)
				(justify left)
			)
		)
		(property "Value" ""
			(at 0 0 0)
			(layer "F.Fab")
			(effects
				(font
					(size 1.27 1.27)
				)
			)
		)
		(duplicate_pad_numbers_are_jumpers no)
		(fp_poly
			(pts
				(xy 0.3048 -0.1016) (xy 0.3048 0.9906) (xy -0.3048 0.9906) (xy -0.3048 -0.1016)
			)
			(stroke
				(width 0)
				(type default)
			)
			(fill no)
			(layer "F.CrtYd")
		)
		(fp_line
			(start -0.3048 -0.1016)
			(end -0.3048 0.9906)
			(stroke
				(width 0.1)
				(type default)
			)
			(layer "F.Fab")
		)
		(fp_line
			(start -0.3048 0.9906)
			(end 0.3048 0.9906)
			(stroke
				(width 0.1)
				(type default)
			)
			(layer "F.Fab")
		)
		(fp_line
			(start 0.3048 -0.1016)
			(end -0.3048 -0.1016)
			(stroke
				(width 0.1)
				(type default)
			)
			(layer "F.Fab")
		)
		(fp_line
			(start 0.3048 0.9906)
			(end 0.3048 -0.1016)
			(stroke
				(width 0.1)
				(type default)
			)
			(layer "F.Fab")
		)
		(pad "1" smd rect
			(at 0 0)
			(size 0.508 0.508)
			(layers "F.Cu" "F.Mask" "F.Paste")
			(net "VR_PVCCIN_CPU0_AIREF4")
		)
		(pad "2" smd rect
			(at 0 0.889)
			(size 0.508 0.508)
			(layers "F.Cu" "F.Mask" "F.Paste")
			(net "GND")
		)
		(zone
			(layer "F.Cu")
			(hatch none 0.5)
			(connect_pads
				(clearance 0)
			)
			(min_thickness 0.25)
			(keepout
				(tracks allowed)
				(vias not_allowed)
				(pads allowed)
				(copperpour not_allowed)
				(footprints allowed)
			)
			(placement
				(enabled no)
				(sheetname "")
			)
			(fill
				(thermal_gap 0.5)
				(thermal_bridge_width 0.5)
				(island_removal_mode 0)
			)
			(polygon
				(pts
					(xy 194.203828 -77.746352) (xy 194.711828 -77.746352) (xy 194.711828 -77.365352) (xy 194.203828 -77.365352)
				)
			)
		)
		(zone
			(layer "F.Cu")
			(hatch none 0.5)
			(connect_pads
				(clearance 0)
			)
			(min_thickness 0.25)
			(keepout
				(tracks not_allowed)
				(vias allowed)
				(pads allowed)
				(copperpour not_allowed)
				(footprints allowed)
			)
			(placement
				(enabled no)
				(sheetname "")
			)
			(fill
				(thermal_gap 0.5)
				(thermal_bridge_width 0.5)
				(island_removal_mode 0)
			)
			(polygon
				(pts
					(xy 194.203828 -77.365352) (xy 194.711828 -77.365352) (xy 194.711828 -77.746352) (xy 194.203828 -77.746352)
				)
			)
		)
	)
	(footprint ""
		(layer "F.Cu")
		(at 18.9484 -118.239794 90)
		(property "Reference" "R1B22"
			(at 0 0 90)
			(layer "F.SilkS")
			(hide yes)
			(effects
				(font
					(size 1.27 1.27)
				)
			)
		)
		(property "Value" ""
			(at 0 0 90)
			(layer "F.Fab")
			(effects
				(font
					(size 1.27 1.27)
				)
			)
		)
		(duplicate_pad_numbers_are_jumpers no)
		(fp_rect
			(start -0.2794 -0.1016)
			(end 0.2794 0.9906)
			(stroke
				(width 0)
				(type default)
			)
			(fill no)
			(layer "F.CrtYd")
		)
		(fp_line
			(start 0.2794 -0.1016)
			(end -0.2794 -0.1016)
			(stroke
				(width 0.1)
				(type default)
			)
			(layer "F.Fab")
		)
		(fp_line
			(start -0.2794 -0.1016)
			(end -0.2794 0.9906)
			(stroke
				(width 0.1)
				(type default)
			)
			(layer "F.Fab")
		)
		(fp_line
			(start 0.2794 0.9906)
			(end 0.2794 -0.1016)
			(stroke
				(width 0.1)
				(type default)
			)
			(layer "F.Fab")
		)
		(fp_line
			(start -0.2794 0.9906)
			(end 0.2794 0.9906)
			(stroke
				(width 0.1)
				(type default)
			)
			(layer "F.Fab")
		)
		(pad "1" smd rect
			(at 0 0 90)
			(size 0.508 0.508)
			(layers "F.Cu" "F.Mask" "F.Paste")
			(net "FAN_TACH2")
		)
		(pad "2" smd rect
			(at 0 0.889 90)
			(size 0.508 0.508)
			(layers "F.Cu" "F.Mask" "F.Paste")
			(net "FAN_TACH2_CPU1_D2")
		)
		(zone
			(layer "F.Cu")
			(hatch none 0.5)
			(connect_pads
				(clearance 0)
			)
			(min_thickness 0.25)
			(keepout
				(tracks allowed)
				(vias not_allowed)
				(pads allowed)
				(copperpour not_allowed)
				(footprints allowed)
			)
			(placement
				(enabled no)
				(sheetname "")
			)
			(fill
				(thermal_gap 0.5)
				(thermal_bridge_width 0.5)
				(island_removal_mode 0)
			)
			(polygon
				(pts
					(xy 19.2024 -117.985794) (xy 19.5834 -117.985794) (xy 19.5834 -118.493794) (xy 19.2024 -118.493794)
				)
			)
		)
		(zone
			(layer "F.Cu")
			(hatch none 0.5)
			(connect_pads
				(clearance 0)
			)
			(min_thickness 0.25)
			(keepout
				(tracks not_allowed)
				(vias allowed)
				(pads allowed)
				(copperpour not_allowed)
				(footprints allowed)
			)
			(placement
				(enabled no)
				(sheetname "")
			)
			(fill
				(thermal_gap 0.5)
				(thermal_bridge_width 0.5)
				(island_removal_mode 0)
			)
			(polygon
				(pts
					(xy 19.2024 -117.985794) (xy 19.5834 -117.985794) (xy 19.5834 -118.493794) (xy 19.2024 -118.493794)
				)
			)
		)
	)
	(footprint ""
		(layer "F.Cu")
		(at 485.875076 -26.326084 180)
		(property "Reference" "R9F70"
			(at 0 0 180)
			(layer "F.SilkS")
			(hide yes)
			(effects
				(font
					(size 1.27 1.27)
				)
			)
		)
		(property "Value" ""
			(at 0 0 180)
			(layer "F.Fab")
			(effects
				(font
					(size 1.27 1.27)
				)
			)
		)
		(duplicate_pad_numbers_are_jumpers no)
		(fp_poly
			(pts
				(xy -0.2794 -0.1016) (xy 0.2794 -0.1016) (xy 0.2794 0.9906) (xy -0.2794 0.9906)
			)
			(stroke
				(width 0)
				(type default)
			)
			(fill no)
			(layer "F.CrtYd")
		)
		(fp_line
			(start 0.2794 0.9906)
			(end 0.2794 -0.1016)
			(stroke
				(width 0.1)
				(type default)
			)
			(layer "F.Fab")
		)
		(fp_line
			(start 0.2794 -0.1016)
			(end -0.2794 -0.1016)
			(stroke
				(width 0.1)
				(type default)
			)
			(layer "F.Fab")
		)
		(fp_line
			(start -0.2794 0.9906)
			(end 0.2794 0.9906)
			(stroke
				(width 0.1)
				(type default)
			)
			(layer "F.Fab")
		)
		(fp_line
			(start -0.2794 -0.1016)
			(end -0.2794 0.9906)
			(stroke
				(width 0.1)
				(type default)
			)
			(layer "F.Fab")
		)
		(pad "1" smd rect
			(at 0 0 180)
			(size 0.508 0.508)
			(layers "F.Cu" "F.Mask" "F.Paste")
			(net "SPA_MID_DBG_TX")
		)
		(pad "2" smd rect
			(at 0 0.889 180)
			(size 0.508 0.508)
			(layers "F.Cu" "F.Mask" "F.Paste")
			(net "SPA_MID_DBG_TX_R")
		)
		(zone
			(layer "F.Cu")
			(hatch none 0.5)
			(connect_pads
				(clearance 0)
			)
			(min_thickness 0.25)
			(keepout
				(tracks not_allowed)
				(vias allowed)
				(pads allowed)
				(copperpour not_allowed)
				(footprints allowed)
			)
			(placement
				(enabled no)
				(sheetname "")
			)
			(fill
				(thermal_gap 0.5)
				(thermal_bridge_width 0.5)
				(island_removal_mode 0)
			)
			(polygon
				(pts
					(xy 486.129076 -26.961084) (xy 485.621076 -26.961084) (xy 485.621076 -26.580084) (xy 486.129076 -26.580084)
				)
			)
		)
		(zone
			(layer "F.Cu")
			(hatch none 0.5)
			(connect_pads
				(clearance 0)
			)
			(min_thickness 0.25)
			(keepout
				(tracks allowed)
				(vias not_allowed)
				(pads allowed)
				(copperpour not_allowed)
				(footprints allowed)
			)
			(placement
				(enabled no)
				(sheetname "")
			)
			(fill
				(thermal_gap 0.5)
				(thermal_bridge_width 0.5)
				(island_removal_mode 0)
			)
			(polygon
				(pts
					(xy 486.129076 -26.580084) (xy 485.621076 -26.580084) (xy 485.621076 -26.961084) (xy 486.129076 -26.961084)
				)
			)
		)
	)
	(footprint ""
		(layer "F.Cu")
		(at 447.3829 -40.2971 90)
		(property "Reference" "R25W94"
			(at -0.8382 -0.67818 90)
			(unlocked yes)
			(layer "F.SilkS")
			(effects
				(font
					(size 0.4064 0.254)
					(thickness 0.1524)
				)
				(justify left)
			)
		)
		(property "Value" ""
			(at 0 0 90)
			(layer "F.Fab")
			(effects
				(font
					(size 1.27 1.27)
				)
			)
		)
		(duplicate_pad_numbers_are_jumpers no)
		(fp_poly
			(pts
				(xy -0.2794 -0.1016) (xy 0.2794 -0.1016) (xy 0.2794 0.9906) (xy -0.2794 0.9906)
			)
			(stroke
				(width 0)
				(type default)
			)
			(fill no)
			(layer "F.CrtYd")
		)
		(fp_line
			(start 0.2794 -0.1016)
			(end -0.2794 -0.1016)
			(stroke
				(width 0.1)
				(type default)
			)
			(layer "F.Fab")
		)
		(fp_line
			(start -0.2794 -0.1016)
			(end -0.2794 0.9906)
			(stroke
				(width 0.1)
				(type default)
			)
			(layer "F.Fab")
		)
		(fp_line
			(start 0.2794 0.9906)
			(end 0.2794 -0.1016)
			(stroke
				(width 0.1)
				(type default)
			)
			(layer "F.Fab")
		)
		(fp_line
			(start -0.2794 0.9906)
			(end 0.2794 0.9906)
			(stroke
				(width 0.1)
				(type default)
			)
			(layer "F.Fab")
		)
		(pad "1" smd rect
			(at 0 0 90)
			(size 0.508 0.508)
			(layers "F.Cu" "F.Mask" "F.Paste")
			(net "GND")
		)
		(pad "2" smd rect
			(at 0 0.889 90)
			(size 0.508 0.508)
			(layers "F.Cu" "F.Mask" "F.Paste")
			(net "PD_SPI_BMC_BT_CS0_N")
		)
		(zone
			(layer "F.Cu")
			(hatch none 0.5)
			(connect_pads
				(clearance 0)
			)
			(min_thickness 0.25)
			(keepout
				(tracks allowed)
				(vias not_allowed)
				(pads allowed)
				(copperpour not_allowed)
				(footprints allowed)
			)
			(placement
				(enabled no)
				(sheetname "")
			)
			(fill
				(thermal_gap 0.5)
				(thermal_bridge_width 0.5)
				(island_removal_mode 0)
			)
			(polygon
				(pts
					(xy 447.6369 -40.0431) (xy 447.6369 -40.5511) (xy 448.0179 -40.5511) (xy 448.0179 -40.0431)
				)
			)
		)
		(zone
			(layer "F.Cu")
			(hatch none 0.5)
			(connect_pads
				(clearance 0)
			)
			(min_thickness 0.25)
			(keepout
				(tracks not_allowed)
				(vias allowed)
				(pads allowed)
				(copperpour not_allowed)
				(footprints allowed)
			)
			(placement
				(enabled no)
				(sheetname "")
			)
			(fill
				(thermal_gap 0.5)
				(thermal_bridge_width 0.5)
				(island_removal_mode 0)
			)
			(polygon
				(pts
					(xy 448.0179 -40.0431) (xy 448.0179 -40.5511) (xy 447.6369 -40.5511) (xy 447.6369 -40.0431)
				)
			)
		)
	)
)
